(kicad_pcb
	(version 20260206)
	(generator "pcbnew")
	(generator_version "10.0")
	(general
		(thickness 1.6)
		(legacy_teardrops no)
	)
	(paper "A4")
	(title_block
		(title "pdpb — Lightning_PDPB_BRD.brd")
		(comment 1 "Lightning (Wiwynn / Facebook NVMe JBOF) / footprints 1097-1103 of 1140")
	)
	(layers
		(0 "F.Cu" signal "TOP")
		(4 "In1.Cu" signal "L2GND")
		(6 "In2.Cu" signal "L3")
		(8 "In3.Cu" signal "L4VCC")
		(10 "In4.Cu" signal "L5VCC")
		(12 "In5.Cu" signal "L6")
		(14 "In6.Cu" signal "L7GND")
		(2 "B.Cu" signal "BOTTOM")
		(9 "F.Adhes" user "F.Adhesive")
		(11 "B.Adhes" user "B.Adhesive")
		(13 "F.Paste" user "Package Geometry/Pastemask Top")
		(15 "B.Paste" user "Package Geometry/Pastemask Bottom")
		(5 "F.SilkS" user "Ref Des/Silkscreen Top")
		(7 "B.SilkS" user "Ref Des/Silkscreen Bottom")
		(1 "F.Mask" user "Board Geometry/Soldermask Top")
		(3 "B.Mask" user "Board Geometry/Soldermask Bottom")
		(17 "Dwgs.User" user "User.Drawings")
		(19 "Cmts.User" user "User.Comments")
		(21 "Eco1.User" user "User.Eco1")
		(23 "Eco2.User" user "User.Eco2")
		(25 "Edge.Cuts" user "Board Geometry/Outline")
		(27 "Margin" user)
		(31 "F.CrtYd" user "Package Geometry/Place Bound Top")
		(29 "B.CrtYd" user "Package Geometry/Place Bound Bottom")
		(35 "F.Fab" user "Ref Des/Assembly Top")
		(33 "B.Fab" user "Ref Des/Assembly Bottom")
	)
	(footprint ""
		(layer "F.Cu")
		(at 39.83355 -307.01615 -90)
		(property "Reference" "R9851"
			(at 0 0 270)
			(layer "F.SilkS")
			(hide yes)
			(effects
				(font
					(size 1.27 1.27)
				)
			)
		)
		(property "Value" "1KR2J-1-GP"
			(at 0.064008 -3.993896 270)
			(unlocked yes)
			(layer "F.Fab")
			(hide yes)
			(effects
				(font
					(size 1.016 1.016)
					(thickness 0.1524)
				)
			)
		)
		(property "Device Type" "R402H16"
			(at 0.064008 -5.517896 270)
			(unlocked yes)
			(layer "F.Fab")
			(hide yes)
			(effects
				(font
					(size 1.016 1.016)
					(thickness 0.1524)
				)
			)
		)
		(duplicate_pad_numbers_are_jumpers no)
		(fp_line
			(start -0.508 -0.9398)
			(end -0.508 0.9398)
			(stroke
				(width 0.1524)
				(type default)
			)
			(layer "F.SilkS")
		)
		(fp_line
			(start 0.508 -0.9398)
			(end -0.508 -0.9398)
			(stroke
				(width 0.1524)
				(type default)
			)
			(layer "F.SilkS")
		)
		(fp_rect
			(start -0.508 0.9398)
			(end 0.508 -0.9398)
			(stroke
				(width 0)
				(type default)
			)
			(fill no)
			(layer "F.CrtYd")
		)
		(fp_rect
			(start -0.508 0.9398)
			(end 0.508 -0.9398)
			(stroke
				(width 0)
				(type default)
			)
			(fill no)
			(layer "F.Fab")
		)
		(pad "1" smd custom
			(at 0 -0.4445 270)
			(size 0.1397 0.1397)
			(layers "F.Cu" "F.Mask" "F.Paste")
			(net "SSD11_PWREN")
			(options
				(clearance outline)
				(anchor circle)
			)
			(primitives
				(gr_poly
					(pts
						(arc
							(start -0.1778 -0.2794)
							(mid -0.249642 -0.249642)
							(end -0.2794 -0.1778)
						)
						(arc
							(start -0.2794 0.1778)
							(mid -0.249642 0.249642)
							(end -0.1778 0.2794)
						)
						(arc
							(start 0.1778 0.2794)
							(mid 0.249642 0.249642)
							(end 0.2794 0.1778)
						)
						(arc
							(start 0.2794 -0.1778)
							(mid 0.249642 -0.249642)
							(end 0.1778 -0.2794)
						)
					)
					(width 0)
					(fill yes)
				)
			)
		)
		(pad "2" smd custom
			(at 0 0.4445 270)
			(size 0.1397 0.1397)
			(layers "F.Cu" "F.Mask" "F.Paste")
			(net "SSD11_PWREN_R")
			(options
				(clearance outline)
				(anchor circle)
			)
			(primitives
				(gr_poly
					(pts
						(arc
							(start -0.1778 -0.2794)
							(mid -0.249642 -0.249642)
							(end -0.2794 -0.1778)
						)
						(arc
							(start -0.2794 0.1778)
							(mid -0.249642 0.249642)
							(end -0.1778 0.2794)
						)
						(arc
							(start 0.1778 0.2794)
							(mid 0.249642 0.249642)
							(end 0.2794 0.1778)
						)
						(arc
							(start 0.2794 -0.1778)
							(mid 0.249642 -0.249642)
							(end 0.1778 -0.2794)
						)
					)
					(width 0)
					(fill yes)
				)
			)
		)
	)
	(footprint ""
		(layer "F.Cu")
		(at 84.455 -300.355 90)
		(property "Reference" "R421"
			(at 0 0 90)
			(layer "F.SilkS")
			(hide yes)
			(effects
				(font
					(size 1.27 1.27)
				)
			)
		)
		(property "Value" "0R2J-2-GP"
			(at 0.064008 -3.993896 90)
			(unlocked yes)
			(layer "F.Fab")
			(hide yes)
			(effects
				(font
					(size 1.016 1.016)
					(thickness 0.1524)
				)
			)
		)
		(property "Device Type" "R402H16"
			(at 0.064008 -5.517896 90)
			(unlocked yes)
			(layer "F.Fab")
			(hide yes)
			(effects
				(font
					(size 1.016 1.016)
					(thickness 0.1524)
				)
			)
		)
		(duplicate_pad_numbers_are_jumpers no)
		(fp_line
			(start 0.508 -0.9398)
			(end -0.508 -0.9398)
			(stroke
				(width 0.1524)
				(type default)
			)
			(layer "F.SilkS")
		)
		(fp_line
			(start -0.508 -0.9398)
			(end -0.508 0.9398)
			(stroke
				(width 0.1524)
				(type default)
			)
			(layer "F.SilkS")
		)
		(fp_rect
			(start -0.508 0.9398)
			(end 0.508 -0.9398)
			(stroke
				(width 0)
				(type default)
			)
			(fill no)
			(layer "F.CrtYd")
		)
		(fp_rect
			(start -0.508 0.9398)
			(end 0.508 -0.9398)
			(stroke
				(width 0)
				(type default)
			)
			(fill no)
			(layer "F.Fab")
		)
		(pad "1" smd custom
			(at 0 -0.4445 90)
			(size 0.1397 0.1397)
			(layers "F.Cu" "F.Mask" "F.Paste")
			(net "BMC_I2C_SCL_BUF_9")
			(options
				(clearance outline)
				(anchor circle)
			)
			(primitives
				(gr_poly
					(pts
						(arc
							(start -0.1778 -0.2794)
							(mid -0.249642 -0.249642)
							(end -0.2794 -0.1778)
						)
						(arc
							(start -0.2794 0.1778)
							(mid -0.249642 0.249642)
							(end -0.1778 0.2794)
						)
						(arc
							(start 0.1778 0.2794)
							(mid 0.249642 0.249642)
							(end 0.2794 0.1778)
						)
						(arc
							(start 0.2794 -0.1778)
							(mid 0.249642 -0.249642)
							(end 0.1778 -0.2794)
						)
					)
					(width 0)
					(fill yes)
				)
			)
		)
		(pad "2" smd custom
			(at 0 0.4445 90)
			(size 0.1397 0.1397)
			(layers "F.Cu" "F.Mask" "F.Paste")
			(net "I2C_SCL_BUF_9_EU2_R")
			(options
				(clearance outline)
				(anchor circle)
			)
			(primitives
				(gr_poly
					(pts
						(arc
							(start -0.1778 -0.2794)
							(mid -0.249642 -0.249642)
							(end -0.2794 -0.1778)
						)
						(arc
							(start -0.2794 0.1778)
							(mid -0.249642 0.249642)
							(end -0.1778 0.2794)
						)
						(arc
							(start 0.1778 0.2794)
							(mid 0.249642 0.249642)
							(end 0.2794 0.1778)
						)
						(arc
							(start 0.2794 -0.1778)
							(mid 0.249642 -0.249642)
							(end 0.1778 -0.2794)
						)
					)
					(width 0)
					(fill yes)
				)
			)
		)
	)
	(footprint ""
		(layer "F.Cu")
		(at 77.7748 -430.3395)
		(property "Reference" "R9958"
			(at 0 0 0)
			(layer "F.SilkS")
			(hide yes)
			(effects
				(font
					(size 1.27 1.27)
				)
			)
		)
		(property "Value" "56R2F-1-GP"
			(at 0.064008 -3.993896 0)
			(unlocked yes)
			(layer "F.Fab")
			(hide yes)
			(effects
				(font
					(size 1.016 1.016)
					(thickness 0.1524)
				)
			)
		)
		(property "Device Type" "R402H16"
			(at 0.064008 -5.517896 0)
			(unlocked yes)
			(layer "F.Fab")
			(hide yes)
			(effects
				(font
					(size 1.016 1.016)
					(thickness 0.1524)
				)
			)
		)
		(duplicate_pad_numbers_are_jumpers no)
		(fp_line
			(start -0.508 -0.9398)
			(end -0.508 0.9398)
			(stroke
				(width 0.1524)
				(type default)
			)
			(layer "F.SilkS")
		)
		(fp_line
			(start 0.508 -0.9398)
			(end -0.508 -0.9398)
			(stroke
				(width 0.1524)
				(type default)
			)
			(layer "F.SilkS")
		)
		(fp_rect
			(start -0.508 0.9398)
			(end 0.508 -0.9398)
			(stroke
				(width 0)
				(type default)
			)
			(fill no)
			(layer "F.CrtYd")
		)
		(fp_rect
			(start -0.508 0.9398)
			(end 0.508 -0.9398)
			(stroke
				(width 0)
				(type default)
			)
			(fill no)
			(layer "F.Fab")
		)
		(pad "1" smd custom
			(at 0 -0.4445)
			(size 0.1397 0.1397)
			(layers "F.Cu" "F.Mask" "F.Paste")
			(net "PE_100M_CLK4_N")
			(options
				(clearance outline)
				(anchor circle)
			)
			(primitives
				(gr_poly
					(pts
						(arc
							(start -0.1778 -0.2794)
							(mid -0.249642 -0.249642)
							(end -0.2794 -0.1778)
						)
						(arc
							(start -0.2794 0.1778)
							(mid -0.249642 0.249642)
							(end -0.1778 0.2794)
						)
						(arc
							(start 0.1778 0.2794)
							(mid 0.249642 0.249642)
							(end 0.2794 0.1778)
						)
						(arc
							(start 0.2794 -0.1778)
							(mid 0.249642 -0.249642)
							(end 0.1778 -0.2794)
						)
					)
					(width 0)
					(fill yes)
				)
			)
		)
		(pad "2" smd custom
			(at 0 0.4445)
			(size 0.1397 0.1397)
			(layers "F.Cu" "F.Mask" "F.Paste")
			(net "GND")
			(options
				(clearance outline)
				(anchor circle)
			)
			(primitives
				(gr_poly
					(pts
						(arc
							(start -0.1778 -0.2794)
							(mid -0.249642 -0.249642)
							(end -0.2794 -0.1778)
						)
						(arc
							(start -0.2794 0.1778)
							(mid -0.249642 0.249642)
							(end -0.1778 0.2794)
						)
						(arc
							(start 0.1778 0.2794)
							(mid 0.249642 0.249642)
							(end 0.2794 0.1778)
						)
						(arc
							(start 0.2794 -0.1778)
							(mid 0.249642 -0.249642)
							(end 0.1778 -0.2794)
						)
					)
					(width 0)
					(fill yes)
				)
			)
		)
	)
	(footprint ""
		(layer "F.Cu")
		(at 30.607 -410.9974 90)
		(property "Reference" "Q77"
			(at 0 0 90)
			(layer "F.SilkS")
			(hide yes)
			(effects
				(font
					(size 1.27 1.27)
				)
			)
		)
		(property "Value" "2N7002A-7-GP"
			(at 0.127 -8.9662 90)
			(unlocked yes)
			(layer "F.Fab")
			(hide yes)
			(effects
				(font
					(size 1.016 1.016)
					(thickness 0.1524)
				)
			)
		)
		(property "Device Type" "SOT23DGS2D4H48"
			(at 0.127 -10.4902 90)
			(unlocked yes)
			(layer "F.Fab")
			(hide yes)
			(effects
				(font
					(size 1.016 1.016)
					(thickness 0.1524)
				)
			)
		)
		(duplicate_pad_numbers_are_jumpers no)
		(fp_line
			(start 1.651 -1.778)
			(end -1.651 -1.778)
			(stroke
				(width 0.1524)
				(type default)
			)
			(layer "F.SilkS")
		)
		(fp_line
			(start -1.651 -1.778)
			(end -1.651 1.778)
			(stroke
				(width 0.1524)
				(type default)
			)
			(layer "F.SilkS")
		)
		(fp_line
			(start 1.651 1.778)
			(end 1.651 -1.778)
			(stroke
				(width 0.1524)
				(type default)
			)
			(layer "F.SilkS")
		)
		(fp_line
			(start -1.651 1.778)
			(end 1.651 1.778)
			(stroke
				(width 0.1524)
				(type default)
			)
			(layer "F.SilkS")
		)
		(fp_poly
			(pts
				(xy -1.778 1.8796) (xy -1.778 -1.8796) (xy 1.778 -1.8796) (xy 1.778 1.8796)
			)
			(stroke
				(width 0)
				(type default)
			)
			(fill no)
			(layer "F.CrtYd")
		)
		(fp_poly
			(pts
				(xy -1.778 1.8796) (xy -1.778 -1.8796) (xy 1.778 -1.8796) (xy 1.778 1.8796)
			)
			(stroke
				(width 0)
				(type default)
			)
			(fill no)
			(layer "F.Fab")
		)
		(pad "D" smd custom
			(at 0 -0.9525 90)
			(size 0.1905 0.1905)
			(layers "F.Cu" "F.Mask" "F.Paste")
			(net "P12V_MOST10_GATE_D")
			(options
				(clearance outline)
				(anchor circle)
			)
			(primitives
				(gr_poly
					(pts
						(arc
							(start -0.1778 0.5715)
							(mid -0.321484 0.511984)
							(end -0.381 0.3683)
						)
						(arc
							(start -0.381 -0.3683)
							(mid -0.321484 -0.511984)
							(end -0.1778 -0.5715)
						)
						(arc
							(start 0.1778 -0.5715)
							(mid 0.321484 -0.511984)
							(end 0.381 -0.3683)
						)
						(arc
							(start 0.381 0.3683)
							(mid 0.321484 0.511984)
							(end 0.1778 0.5715)
						)
					)
					(width 0)
					(fill yes)
				)
			)
		)
		(pad "G" smd custom
			(at -0.98425 0.9525 90)
			(size 0.1905 0.1905)
			(layers "F.Cu" "F.Mask" "F.Paste")
			(net "P12V_MOST10_GATE")
			(options
				(clearance outline)
				(anchor circle)
			)
			(primitives
				(gr_poly
					(pts
						(arc
							(start -0.1778 0.5715)
							(mid -0.321484 0.511984)
							(end -0.381 0.3683)
						)
						(arc
							(start -0.381 -0.3683)
							(mid -0.321484 -0.511984)
							(end -0.1778 -0.5715)
						)
						(arc
							(start 0.1778 -0.5715)
							(mid 0.321484 -0.511984)
							(end 0.381 -0.3683)
						)
						(arc
							(start 0.381 0.3683)
							(mid 0.321484 0.511984)
							(end 0.1778 0.5715)
						)
					)
					(width 0)
					(fill yes)
				)
			)
		)
		(pad "S" smd custom
			(at 0.98425 0.9525 90)
			(size 0.1905 0.1905)
			(layers "F.Cu" "F.Mask" "F.Paste")
			(net "GND")
			(options
				(clearance outline)
				(anchor circle)
			)
			(primitives
				(gr_poly
					(pts
						(arc
							(start -0.1778 0.5715)
							(mid -0.321484 0.511984)
							(end -0.381 0.3683)
						)
						(arc
							(start -0.381 -0.3683)
							(mid -0.321484 -0.511984)
							(end -0.1778 -0.5715)
						)
						(arc
							(start 0.1778 -0.5715)
							(mid 0.321484 -0.511984)
							(end 0.381 -0.3683)
						)
						(arc
							(start 0.381 0.3683)
							(mid 0.321484 0.511984)
							(end 0.1778 0.5715)
						)
					)
					(width 0)
					(fill yes)
				)
			)
		)
	)
	(footprint ""
		(layer "F.Cu")
		(at 73.914 -354.965 180)
		(property "Reference" "R430"
			(at 0 0 180)
			(layer "F.SilkS")
			(hide yes)
			(effects
				(font
					(size 1.27 1.27)
				)
			)
		)
		(property "Value" "0R2J-2-GP"
			(at 0.064008 -3.993896 180)
			(unlocked yes)
			(layer "F.Fab")
			(hide yes)
			(effects
				(font
					(size 1.016 1.016)
					(thickness 0.1524)
				)
			)
		)
		(property "Device Type" "R402H16"
			(at 0.064008 -5.517896 180)
			(unlocked yes)
			(layer "F.Fab")
			(hide yes)
			(effects
				(font
					(size 1.016 1.016)
					(thickness 0.1524)
				)
			)
		)
		(duplicate_pad_numbers_are_jumpers no)
		(fp_line
			(start 0.508 -0.9398)
			(end -0.508 -0.9398)
			(stroke
				(width 0.1524)
				(type default)
			)
			(layer "F.SilkS")
		)
		(fp_line
			(start -0.508 -0.9398)
			(end -0.508 0.9398)
			(stroke
				(width 0.1524)
				(type default)
			)
			(layer "F.SilkS")
		)
		(fp_rect
			(start -0.508 0.9398)
			(end 0.508 -0.9398)
			(stroke
				(width 0)
				(type default)
			)
			(fill no)
			(layer "F.CrtYd")
		)
		(fp_rect
			(start -0.508 0.9398)
			(end 0.508 -0.9398)
			(stroke
				(width 0)
				(type default)
			)
			(fill no)
			(layer "F.Fab")
		)
		(pad "1" smd custom
			(at 0 -0.4445 180)
			(size 0.1397 0.1397)
			(layers "F.Cu" "F.Mask" "F.Paste")
			(net "BMC_I2C_SDA_BUF_9")
			(options
				(clearance outline)
				(anchor circle)
			)
			(primitives
				(gr_poly
					(pts
						(arc
							(start -0.1778 -0.2794)
							(mid -0.249642 -0.249642)
							(end -0.2794 -0.1778)
						)
						(arc
							(start -0.2794 0.1778)
							(mid -0.249642 0.249642)
							(end -0.1778 0.2794)
						)
						(arc
							(start 0.1778 0.2794)
							(mid 0.249642 0.249642)
							(end 0.2794 0.1778)
						)
						(arc
							(start 0.2794 -0.1778)
							(mid 0.249642 -0.249642)
							(end 0.1778 -0.2794)
						)
					)
					(width 0)
					(fill yes)
				)
			)
		)
		(pad "2" smd custom
			(at 0 0.4445 180)
			(size 0.1397 0.1397)
			(layers "F.Cu" "F.Mask" "F.Paste")
			(net "I2C8_SDA_R_SW_EU17")
			(options
				(clearance outline)
				(anchor circle)
			)
			(primitives
				(gr_poly
					(pts
						(arc
							(start -0.1778 -0.2794)
							(mid -0.249642 -0.249642)
							(end -0.2794 -0.1778)
						)
						(arc
							(start -0.2794 0.1778)
							(mid -0.249642 0.249642)
							(end -0.1778 0.2794)
						)
						(arc
							(start 0.1778 0.2794)
							(mid 0.249642 0.249642)
							(end 0.2794 0.1778)
						)
						(arc
							(start 0.2794 -0.1778)
							(mid 0.249642 -0.249642)
							(end 0.1778 -0.2794)
						)
					)
					(width 0)
					(fill yes)
				)
			)
		)
	)
	(footprint ""
		(layer "F.Cu")
		(at 49.022 -452.501 -90)
		(property "Reference" "R9897"
			(at 0 0 270)
			(layer "F.SilkS")
			(hide yes)
			(effects
				(font
					(size 1.27 1.27)
				)
			)
		)
		(property "Value" "1K82R2F-1-GP"
			(at 0.064008 -3.993896 270)
			(unlocked yes)
			(layer "F.Fab")
			(hide yes)
			(effects
				(font
					(size 1.016 1.016)
					(thickness 0.1524)
				)
			)
		)
		(property "Device Type" "R402H16"
			(at 0.064008 -5.517896 270)
			(unlocked yes)
			(layer "F.Fab")
			(hide yes)
			(effects
				(font
					(size 1.016 1.016)
					(thickness 0.1524)
				)
			)
		)
		(duplicate_pad_numbers_are_jumpers no)
		(fp_line
			(start -0.508 -0.9398)
			(end -0.508 0.9398)
			(stroke
				(width 0.1524)
				(type default)
			)
			(layer "F.SilkS")
		)
		(fp_line
			(start 0.508 -0.9398)
			(end -0.508 -0.9398)
			(stroke
				(width 0.1524)
				(type default)
			)
			(layer "F.SilkS")
		)
		(fp_rect
			(start -0.508 0.9398)
			(end 0.508 -0.9398)
			(stroke
				(width 0)
				(type default)
			)
			(fill no)
			(layer "F.CrtYd")
		)
		(fp_rect
			(start -0.508 0.9398)
			(end 0.508 -0.9398)
			(stroke
				(width 0)
				(type default)
			)
			(fill no)
			(layer "F.Fab")
		)
		(pad "1" smd custom
			(at 0 -0.4445 270)
			(size 0.1397 0.1397)
			(layers "F.Cu" "F.Mask" "F.Paste")
			(net "P12V")
			(options
				(clearance outline)
				(anchor circle)
			)
			(primitives
				(gr_poly
					(pts
						(arc
							(start -0.1778 -0.2794)
							(mid -0.249642 -0.249642)
							(end -0.2794 -0.1778)
						)
						(arc
							(start -0.2794 0.1778)
							(mid -0.249642 0.249642)
							(end -0.1778 0.2794)
						)
						(arc
							(start 0.1778 0.2794)
							(mid 0.249642 0.249642)
							(end 0.2794 0.1778)
						)
						(arc
							(start 0.2794 -0.1778)
							(mid 0.249642 -0.249642)
							(end 0.1778 -0.2794)
						)
					)
					(width 0)
					(fill yes)
				)
			)
		)
		(pad "2" smd custom
			(at 0 0.4445 270)
			(size 0.1397 0.1397)
			(layers "F.Cu" "F.Mask" "F.Paste")
			(net "DRV_ACT_5")
			(options
				(clearance outline)
				(anchor circle)
			)
			(primitives
				(gr_poly
					(pts
						(arc
							(start -0.1778 -0.2794)
							(mid -0.249642 -0.249642)
							(end -0.2794 -0.1778)
						)
						(arc
							(start -0.2794 0.1778)
							(mid -0.249642 0.249642)
							(end -0.1778 0.2794)
						)
						(arc
							(start 0.1778 0.2794)
							(mid 0.249642 0.249642)
							(end 0.2794 0.1778)
						)
						(arc
							(start 0.2794 -0.1778)
							(mid 0.249642 -0.249642)
							(end 0.1778 -0.2794)
						)
					)
					(width 0)
					(fill yes)
				)
			)
		)
	)
	(footprint ""
		(layer "F.Cu")
		(at 38.241478 -35.052)
		(property "Reference" "R9921"
			(at 0 0 0)
			(layer "F.SilkS")
			(hide yes)
			(effects
				(font
					(size 1.27 1.27)
				)
			)
		)
		(property "Value" "47KR2J-2-GP"
			(at 0.064008 -3.993896 0)
			(unlocked yes)
			(layer "F.Fab")
			(hide yes)
			(effects
				(font
					(size 1.016 1.016)
					(thickness 0.1524)
				)
			)
		)
		(property "Device Type" "R402H16"
			(at 0.064008 -5.517896 0)
			(unlocked yes)
			(layer "F.Fab")
			(hide yes)
			(effects
				(font
					(size 1.016 1.016)
					(thickness 0.1524)
				)
			)
		)
		(duplicate_pad_numbers_are_jumpers no)
		(fp_line
			(start -0.508 -0.9398)
			(end -0.508 0.9398)
			(stroke
				(width 0.1524)
				(type default)
			)
			(layer "F.SilkS")
		)
		(fp_line
			(start 0.508 -0.9398)
			(end -0.508 -0.9398)
			(stroke
				(width 0.1524)
				(type default)
			)
			(layer "F.SilkS")
		)
		(fp_rect
			(start -0.508 0.9398)
			(end 0.508 -0.9398)
			(stroke
				(width 0)
				(type default)
			)
			(fill no)
			(layer "F.CrtYd")
		)
		(fp_rect
			(start -0.508 0.9398)
			(end 0.508 -0.9398)
			(stroke
				(width 0)
				(type default)
			)
			(fill no)
			(layer "F.Fab")
		)
		(pad "1" smd custom
			(at 0 -0.4445)
			(size 0.1397 0.1397)
			(layers "F.Cu" "F.Mask" "F.Paste")
			(net "P3V3")
			(options
				(clearance outline)
				(anchor circle)
			)
			(primitives
				(gr_poly
					(pts
						(arc
							(start -0.1778 -0.2794)
							(mid -0.249642 -0.249642)
							(end -0.2794 -0.1778)
						)
						(arc
							(start -0.2794 0.1778)
							(mid -0.249642 0.249642)
							(end -0.1778 0.2794)
						)
						(arc
							(start 0.1778 0.2794)
							(mid 0.249642 0.249642)
							(end 0.2794 0.1778)
						)
						(arc
							(start 0.2794 -0.1778)
							(mid 0.249642 -0.249642)
							(end 0.1778 -0.2794)
						)
					)
					(width 0)
					(fill yes)
				)
			)
		)
		(pad "2" smd custom
			(at 0 0.4445)
			(size 0.1397 0.1397)
			(layers "F.Cu" "F.Mask" "F.Paste")
			(net "ATTN_LED_DR9_N")
			(options
				(clearance outline)
				(anchor circle)
			)
			(primitives
				(gr_poly
					(pts
						(arc
							(start -0.1778 -0.2794)
							(mid -0.249642 -0.249642)
							(end -0.2794 -0.1778)
						)
						(arc
							(start -0.2794 0.1778)
							(mid -0.249642 0.249642)
							(end -0.1778 0.2794)
						)
						(arc
							(start 0.1778 0.2794)
							(mid 0.249642 0.249642)
							(end 0.2794 0.1778)
						)
						(arc
							(start 0.2794 -0.1778)
							(mid 0.249642 -0.249642)
							(end 0.1778 -0.2794)
						)
					)
					(width 0)
					(fill yes)
				)
			)
		)
	)
)
